(kicad_pcb
	(version 20260206)
	(generator "pcbnew")
	(generator_version "10.0")
	(general
		(thickness 1.21888)
		(legacy_teardrops no)
	)
	(paper "A4")
	(title_block
		(title "timecard-v7 — TimeCard-DC-V7_EXP.PcbDoc")
		(comment 1 "Time Appliance Project (Time Card) / footprints 148-160 of 160")
	)
	(layers
		(0 "F.Cu" signal "TOP")
		(4 "In1.Cu" signal "SGND")
		(6 "In2.Cu" signal "IN1")
		(8 "In3.Cu" signal "IN2")
		(10 "In4.Cu" signal "SGND1")
		(2 "B.Cu" signal "BOTTOM")
		(9 "F.Adhes" user "F.Adhesive")
		(11 "B.Adhes" user "B.Adhesive")
		(13 "F.Paste" user "Top Paste")
		(15 "B.Paste" user "Bottom Paste")
		(5 "F.SilkS" user "Top Overlay")
		(7 "B.SilkS" user "Bottom Overlay")
		(1 "F.Mask" user "Top Solder")
		(3 "B.Mask" user "Bottom Solder")
		(17 "Dwgs.User" user "User.Drawings")
		(19 "Cmts.User" user "User.Comments")
		(21 "Eco1.User" user "User.Eco1")
		(23 "Eco2.User" user "User.Eco2")
		(25 "Edge.Cuts" user)
		(27 "Margin" user)
		(31 "F.CrtYd" user "Top Courtyard")
		(29 "B.CrtYd" user "Bottom Courtyard")
		(35 "F.Fab" user "Top Component Center")
		(33 "B.Fab" user "Bottom Component Center")
	)
	(footprint "Resistors:RESC1608X50N"
		(layer "F.Cu")
		(at 220.8637 85.1662)
		(property "Reference" "R1"
			(at 2.4 0.393345 0)
			(unlocked yes)
			(layer "F.SilkS")
			(effects
				(font
					(size 0.762 0.762)
					(thickness 0.2286)
				)
				(justify left bottom)
			)
		)
		(property "Value" "ERJ-3EKF2000V"
			(at -19.0909 11.38359 0)
			(unlocked yes)
			(layer "F.SilkS")
			(hide yes)
			(effects
				(font
					(size 1.524 1.524)
					(thickness 0.254)
				)
				(justify left bottom)
			)
		)
		(sheetname "POWER")
		(sheetfile "POWER.kicad_sch")
		(duplicate_pad_numbers_are_jumpers no)
		(fp_line
			(start 0 0.5)
			(end 0 -0.5)
			(stroke
				(width 0.1524)
				(type solid)
			)
			(layer "F.SilkS")
		)
		(pad "1" smd rect
			(at -0.69 0 90)
			(size 1 0.72)
			(layers "F.Cu" "F.Mask" "F.Paste")
			(net "GND")
		)
		(pad "2" smd rect
			(at 0.69 0 90)
			(size 1 0.72)
			(layers "F.Cu" "F.Mask" "F.Paste")
			(net "NetD4_1")
		)
	)
	(footprint "Vault:RESC1608X55X30NL15T15"
		(layer "F.Cu")
		(at 83.3761 89.6162)
		(property "Reference" "R41"
			(at -2.521405 0.026921 0)
			(unlocked yes)
			(layer "F.SilkS")
			(effects
				(font
					(size 0.762 0.762)
					(thickness 0.2286)
				)
			)
		)
		(property "Value" "4.7K"
			(at 1.63744 2.352802 0)
			(unlocked yes)
			(layer "F.SilkS")
			(hide yes)
			(effects
				(font
					(size 1.524 1.524)
					(thickness 0.254)
				)
			)
		)
		(sheetname "USER_IO_STATUS")
		(sheetfile "USER_IO_STATUS.kicad_sch")
		(duplicate_pad_numbers_are_jumpers no)
		(pad "1" smd rect
			(at -0.75 0 90)
			(size 0.95 0.95)
			(layers "F.Cu" "F.Mask" "F.Paste")
			(net "GND")
		)
		(pad "2" smd rect
			(at 0.75 0 90)
			(size 0.95 0.95)
			(layers "F.Cu" "F.Mask" "F.Paste")
			(net "NetR41_2")
		)
	)
	(footprint "Vault:FP-STPS5L60S-MFG"
		(layer "F.Cu")
		(at 234.0261 112.9162 90)
		(property "Reference" "D12"
			(at -0.354005 4.546148 270)
			(unlocked yes)
			(layer "F.SilkS")
			(effects
				(font
					(size 1.524 1.524)
					(thickness 0.254)
				)
			)
		)
		(property "Value" "STPS5L60S"
			(at -6.518402 3.795165 0)
			(unlocked yes)
			(layer "F.SilkS")
			(hide yes)
			(effects
				(font
					(size 1.524 1.524)
					(thickness 0.254)
				)
			)
		)
		(sheetname "POWER")
		(sheetfile "POWER.kicad_sch")
		(duplicate_pad_numbers_are_jumpers no)
		(fp_line
			(start 3.575 -3.125)
			(end 3.575 -2.025)
			(stroke
				(width 0.2)
				(type solid)
			)
			(layer "F.SilkS")
		)
		(fp_line
			(start -3.575 -3.125)
			(end 3.575 -3.125)
			(stroke
				(width 0.2)
				(type solid)
			)
			(layer "F.SilkS")
		)
		(fp_line
			(start -3.575 -3.125)
			(end -3.575 -2.025)
			(stroke
				(width 0.2)
				(type solid)
			)
			(layer "F.SilkS")
		)
		(fp_line
			(start 3.575 2.025)
			(end 3.575 3.125)
			(stroke
				(width 0.2)
				(type solid)
			)
			(layer "F.SilkS")
		)
		(fp_line
			(start -3.575 2.025)
			(end -3.575 3.125)
			(stroke
				(width 0.2)
				(type solid)
			)
			(layer "F.SilkS")
		)
		(fp_line
			(start -3.575 3.125)
			(end 3.575 3.125)
			(stroke
				(width 0.2)
				(type solid)
			)
			(layer "F.SilkS")
		)
		(fp_circle
			(center -4.7 -0.025)
			(end -4.575 -0.025)
			(stroke
				(width 0.25)
				(type solid)
			)
			(fill no)
			(layer "F.SilkS")
		)
		(fp_line
			(start 4.195 -3.225)
			(end 4.195 3.225)
			(stroke
				(width 0.2)
				(type solid)
			)
			(layer "F.CrtYd")
		)
		(fp_line
			(start -4.195 -3.225)
			(end 4.195 -3.225)
			(stroke
				(width 0.2)
				(type solid)
			)
			(layer "F.CrtYd")
		)
		(fp_line
			(start -4.195 -3.225)
			(end -4.195 3.225)
			(stroke
				(width 0.2)
				(type solid)
			)
			(layer "F.CrtYd")
		)
		(fp_line
			(start -4.195 3.225)
			(end 4.195 3.225)
			(stroke
				(width 0.2)
				(type solid)
			)
			(layer "F.CrtYd")
		)
		(fp_line
			(start 4.195 -3.225)
			(end 4.195 3.225)
			(stroke
				(width 0.2)
				(type solid)
			)
			(layer "F.Fab")
		)
		(fp_line
			(start -4.195 -3.225)
			(end 4.195 -3.225)
			(stroke
				(width 0.2)
				(type solid)
			)
			(layer "F.Fab")
		)
		(fp_line
			(start -4.195 -3.225)
			(end -4.195 3.225)
			(stroke
				(width 0.2)
				(type solid)
			)
			(layer "F.Fab")
		)
		(fp_line
			(start 0 -0.5)
			(end 0 0.5)
			(stroke
				(width 0.1)
				(type solid)
			)
			(layer "F.Fab")
		)
		(fp_line
			(start -0.5 0)
			(end 0.5 0)
			(stroke
				(width 0.1)
				(type solid)
			)
			(layer "F.Fab")
		)
		(fp_line
			(start -4.195 3.225)
			(end 4.195 3.225)
			(stroke
				(width 0.2)
				(type solid)
			)
			(layer "F.Fab")
		)
		(fp_text user "${REFERENCE}"
			(at -0.00001 0.10711 90)
			(unlocked yes)
			(layer "F.Fab")
			(effects
				(font
					(face "Arial")
					(size 0.63 0.63)
					(thickness 0.1)
				)
				(justify left bottom)
			)
		)
		(pad "1" smd rect
			(at -3.325 0 90)
			(size 1.54 3.14)
			(layers "F.Cu" "F.Mask" "F.Paste")
			(net "NetD12_1")
			(solder_mask_margin 0)
			(solder_paste_margin 0)
		)
		(pad "2" smd rect
			(at 3.325 0 90)
			(size 1.54 3.14)
			(layers "F.Cu" "F.Mask" "F.Paste")
			(net "NetD12_2")
			(solder_mask_margin 0)
			(solder_paste_margin 0)
		)
	)
	(footprint "Capacitors:CAPC1005X06N"
		(layer "B.Cu")
		(at 115.5621 151.7886 90)
		(property "Reference" "C44"
			(at 2.885 -1.204345 270)
			(unlocked yes)
			(layer "B.SilkS")
			(effects
				(font
					(size 0.762 0.762)
					(thickness 0.2286)
				)
				(justify left bottom mirror)
			)
		)
		(property "Value" "CAP_0402_0.1UF_50V"
			(at -3.47599 0.2921 0)
			(unlocked yes)
			(layer "B.SilkS")
			(hide yes)
			(effects
				(font
					(size 1.524 1.524)
					(thickness 0.254)
				)
				(justify left bottom mirror)
			)
		)
		(sheetname "PCIe_JTAG")
		(sheetfile "PCIe_JTAG.kicad_sch")
		(duplicate_pad_numbers_are_jumpers no)
		(pad "1" smd rect
			(at -0.43 0)
			(size 0.64 0.68)
			(layers "B.Cu" "B.Mask" "B.Paste")
			(net "NetC44_1")
		)
		(pad "2" smd rect
			(at 0.43 0)
			(size 0.64 0.68)
			(layers "B.Cu" "B.Mask" "B.Paste")
			(net "PCIE_CLK_P")
		)
	)
	(footprint "Capacitors:CAPC1005X06N"
		(layer "B.Cu")
		(at 127.5001 151.7886 90)
		(property "Reference" "C50"
			(at 2.41349 -0.766255 270)
			(unlocked yes)
			(layer "B.SilkS")
			(effects
				(font
					(size 0.762 0.762)
					(thickness 0.2286)
				)
				(justify left bottom mirror)
			)
		)
		(property "Value" "CAP_0402_0.1UF_50V"
			(at -3.47599 0.2921 0)
			(unlocked yes)
			(layer "B.SilkS")
			(hide yes)
			(effects
				(font
					(size 1.524 1.524)
					(thickness 0.254)
				)
				(justify left bottom mirror)
			)
		)
		(sheetname "PCIe_JTAG")
		(sheetfile "PCIe_JTAG.kicad_sch")
		(duplicate_pad_numbers_are_jumpers no)
		(pad "1" smd rect
			(at -0.43 0)
			(size 0.64 0.68)
			(layers "B.Cu" "B.Mask" "B.Paste")
			(net "NetC50_1")
		)
		(pad "2" smd rect
			(at 0.43 0)
			(size 0.64 0.68)
			(layers "B.Cu" "B.Mask" "B.Paste")
			(net "PCIE_TX2_P")
		)
	)
	(footprint "Capacitors:CAPC1005X06N"
		(layer "B.Cu")
		(at 119.6769 151.7886 90)
		(property "Reference" "C47"
			(at 2.41349 0.097345 270)
			(unlocked yes)
			(layer "B.SilkS")
			(effects
				(font
					(size 0.762 0.762)
					(thickness 0.2286)
				)
				(justify left bottom mirror)
			)
		)
		(property "Value" "CAP_0402_0.1UF_50V"
			(at -3.47599 0.2921 0)
			(unlocked yes)
			(layer "B.SilkS")
			(hide yes)
			(effects
				(font
					(size 1.524 1.524)
					(thickness 0.254)
				)
				(justify left bottom mirror)
			)
		)
		(sheetname "PCIe_JTAG")
		(sheetfile "PCIe_JTAG.kicad_sch")
		(duplicate_pad_numbers_are_jumpers no)
		(pad "1" smd rect
			(at -0.43 0)
			(size 0.64 0.68)
			(layers "B.Cu" "B.Mask" "B.Paste")
			(net "NetC47_1")
		)
		(pad "2" smd rect
			(at 0.43 0)
			(size 0.64 0.68)
			(layers "B.Cu" "B.Mask" "B.Paste")
			(net "PCIE_TX0_N")
		)
	)
	(footprint "Capacitors:CAPC1005X06N"
		(layer "B.Cu")
		(at 116.5781 151.7886 90)
		(property "Reference" "C45"
			(at 2.835 -0.445345 270)
			(unlocked yes)
			(layer "B.SilkS")
			(effects
				(font
					(size 0.762 0.762)
					(thickness 0.2286)
				)
				(justify left bottom mirror)
			)
		)
		(property "Value" "CAP_0402_0.1UF_50V"
			(at -3.47599 0.2921 0)
			(unlocked yes)
			(layer "B.SilkS")
			(hide yes)
			(effects
				(font
					(size 1.524 1.524)
					(thickness 0.254)
				)
				(justify left bottom mirror)
			)
		)
		(sheetname "PCIe_JTAG")
		(sheetfile "PCIe_JTAG.kicad_sch")
		(duplicate_pad_numbers_are_jumpers no)
		(pad "1" smd rect
			(at -0.43 0)
			(size 0.64 0.68)
			(layers "B.Cu" "B.Mask" "B.Paste")
			(net "NetC45_1")
		)
		(pad "2" smd rect
			(at 0.43 0)
			(size 0.64 0.68)
			(layers "B.Cu" "B.Mask" "B.Paste")
			(net "PCIE_CLK_N")
		)
	)
	(footprint "Capacitors:CAPC1005X06N"
		(layer "B.Cu")
		(at 123.5631 151.7886 90)
		(property "Reference" "C48"
			(at 2.41349 -0.867855 270)
			(unlocked yes)
			(layer "B.SilkS")
			(effects
				(font
					(size 0.762 0.762)
					(thickness 0.2286)
				)
				(justify left bottom mirror)
			)
		)
		(property "Value" "CAP_0402_0.1UF_50V"
			(at -3.47599 0.2921 0)
			(unlocked yes)
			(layer "B.SilkS")
			(hide yes)
			(effects
				(font
					(size 1.524 1.524)
					(thickness 0.254)
				)
				(justify left bottom mirror)
			)
		)
		(sheetname "PCIe_JTAG")
		(sheetfile "PCIe_JTAG.kicad_sch")
		(duplicate_pad_numbers_are_jumpers no)
		(pad "1" smd rect
			(at -0.43 0)
			(size 0.64 0.68)
			(layers "B.Cu" "B.Mask" "B.Paste")
			(net "NetC48_1")
		)
		(pad "2" smd rect
			(at 0.43 0)
			(size 0.64 0.68)
			(layers "B.Cu" "B.Mask" "B.Paste")
			(net "PCIE_TX1_P")
		)
	)
	(footprint "Capacitors:CAPC1005X06N"
		(layer "B.Cu")
		(at 132.5801 151.7886 90)
		(property "Reference" "C53"
			(at 2.41349 0.046545 270)
			(unlocked yes)
			(layer "B.SilkS")
			(effects
				(font
					(size 0.762 0.762)
					(thickness 0.2286)
				)
				(justify left bottom mirror)
			)
		)
		(property "Value" "CAP_0402_0.1UF_50V"
			(at -3.47599 0.2921 0)
			(unlocked yes)
			(layer "B.SilkS")
			(hide yes)
			(effects
				(font
					(size 1.524 1.524)
					(thickness 0.254)
				)
				(justify left bottom mirror)
			)
		)
		(sheetname "PCIe_JTAG")
		(sheetfile "PCIe_JTAG.kicad_sch")
		(duplicate_pad_numbers_are_jumpers no)
		(pad "1" smd rect
			(at -0.43 0)
			(size 0.64 0.68)
			(layers "B.Cu" "B.Mask" "B.Paste")
			(net "NetC53_1")
		)
		(pad "2" smd rect
			(at 0.43 0)
			(size 0.64 0.68)
			(layers "B.Cu" "B.Mask" "B.Paste")
			(net "PCIE_TX3_N")
		)
	)
	(footprint "Capacitors:CAPC1005X06N"
		(layer "B.Cu")
		(at 124.5791 151.7886 90)
		(property "Reference" "C49"
			(at 2.41349 -0.156655 270)
			(unlocked yes)
			(layer "B.SilkS")
			(effects
				(font
					(size 0.762 0.762)
					(thickness 0.2286)
				)
				(justify left bottom mirror)
			)
		)
		(property "Value" "CAP_0402_0.1UF_50V"
			(at -3.47599 0.2921 0)
			(unlocked yes)
			(layer "B.SilkS")
			(hide yes)
			(effects
				(font
					(size 1.524 1.524)
					(thickness 0.254)
				)
				(justify left bottom mirror)
			)
		)
		(sheetname "PCIe_JTAG")
		(sheetfile "PCIe_JTAG.kicad_sch")
		(duplicate_pad_numbers_are_jumpers no)
		(pad "1" smd rect
			(at -0.43 0)
			(size 0.64 0.68)
			(layers "B.Cu" "B.Mask" "B.Paste")
			(net "NetC49_1")
		)
		(pad "2" smd rect
			(at 0.43 0)
			(size 0.64 0.68)
			(layers "B.Cu" "B.Mask" "B.Paste")
			(net "PCIE_TX1_N")
		)
	)
	(footprint "Capacitors:CAPC1005X06N"
		(layer "B.Cu")
		(at 131.5641 151.7886 90)
		(property "Reference" "C52"
			(at 2.41349 -0.613855 270)
			(unlocked yes)
			(layer "B.SilkS")
			(effects
				(font
					(size 0.762 0.762)
					(thickness 0.2286)
				)
				(justify left bottom mirror)
			)
		)
		(property "Value" "CAP_0402_0.1UF_50V"
			(at -3.47599 0.2921 0)
			(unlocked yes)
			(layer "B.SilkS")
			(hide yes)
			(effects
				(font
					(size 1.524 1.524)
					(thickness 0.254)
				)
				(justify left bottom mirror)
			)
		)
		(sheetname "PCIe_JTAG")
		(sheetfile "PCIe_JTAG.kicad_sch")
		(duplicate_pad_numbers_are_jumpers no)
		(pad "1" smd rect
			(at -0.43 0)
			(size 0.64 0.68)
			(layers "B.Cu" "B.Mask" "B.Paste")
			(net "NetC52_1")
		)
		(pad "2" smd rect
			(at 0.43 0)
			(size 0.64 0.68)
			(layers "B.Cu" "B.Mask" "B.Paste")
			(net "PCIE_TX3_P")
		)
	)
	(footprint "Capacitors:CAPC1005X06N"
		(layer "B.Cu")
		(at 118.5847 151.7886 90)
		(property "Reference" "C46"
			(at 2.41349 -0.563055 270)
			(unlocked yes)
			(layer "B.SilkS")
			(effects
				(font
					(size 0.762 0.762)
					(thickness 0.2286)
				)
				(justify left bottom mirror)
			)
		)
		(property "Value" "CAP_0402_0.1UF_50V"
			(at -3.47599 0.2921 0)
			(unlocked yes)
			(layer "B.SilkS")
			(hide yes)
			(effects
				(font
					(size 1.524 1.524)
					(thickness 0.254)
				)
				(justify left bottom mirror)
			)
		)
		(sheetname "PCIe_JTAG")
		(sheetfile "PCIe_JTAG.kicad_sch")
		(duplicate_pad_numbers_are_jumpers no)
		(pad "1" smd rect
			(at -0.43 0)
			(size 0.64 0.68)
			(layers "B.Cu" "B.Mask" "B.Paste")
			(net "NetC46_1")
		)
		(pad "2" smd rect
			(at 0.43 0)
			(size 0.64 0.68)
			(layers "B.Cu" "B.Mask" "B.Paste")
			(net "PCIE_TX0_P")
		)
	)
	(footprint "Capacitors:CAPC1005X06N"
		(layer "B.Cu")
		(at 128.3891 151.7886 90)
		(property "Reference" "C51"
			(at 2.41349 0.148145 270)
			(unlocked yes)
			(layer "B.SilkS")
			(effects
				(font
					(size 0.762 0.762)
					(thickness 0.2286)
				)
				(justify left bottom mirror)
			)
		)
		(property "Value" "CAP_0402_0.1UF_50V"
			(at -3.47599 0.2921 0)
			(unlocked yes)
			(layer "B.SilkS")
			(hide yes)
			(effects
				(font
					(size 1.524 1.524)
					(thickness 0.254)
				)
				(justify left bottom mirror)
			)
		)
		(sheetname "PCIe_JTAG")
		(sheetfile "PCIe_JTAG.kicad_sch")
		(duplicate_pad_numbers_are_jumpers no)
		(pad "1" smd rect
			(at -0.43 0)
			(size 0.64 0.68)
			(layers "B.Cu" "B.Mask" "B.Paste")
			(net "NetC51_1")
		)
		(pad "2" smd rect
			(at 0.43 0)
			(size 0.64 0.68)
			(layers "B.Cu" "B.Mask" "B.Paste")
			(net "PCIE_TX2_N")
		)
	)
)
